(kicad_pcb
	(version 20260206)
	(generator "pcbnew")
	(generator_version "10.0")
	(general
		(thickness 1.6)
		(legacy_teardrops no)
	)
	(paper "A4")
	(title_block
		(title "01162023_DA0F0TEBIF0_F0T_Expander_BD_F_brd_V02_OCP.brd")
		(comment 1 "Grand Teton / footprints 8043-8048 of 9728")
	)
	(layers
		(0 "F.Cu" signal "TOP")
		(4 "In1.Cu" signal "GND")
		(6 "In2.Cu" signal "VCC")
		(8 "In3.Cu" signal "VCC1")
		(10 "In4.Cu" signal "GND1")
		(12 "In5.Cu" signal "IN1")
		(14 "In6.Cu" signal "GND2")
		(16 "In7.Cu" signal "IN2")
		(18 "In8.Cu" signal "GND3")
		(20 "In9.Cu" signal "IN3")
		(22 "In10.Cu" signal "GND4")
		(24 "In11.Cu" signal "IN4")
		(26 "In12.Cu" signal "GND5")
		(28 "In13.Cu" signal "IN5")
		(30 "In14.Cu" signal "GND6")
		(32 "In15.Cu" signal "IN6")
		(34 "In16.Cu" signal "GND7")
		(2 "B.Cu" signal "BOTTOM")
		(9 "F.Adhes" user "F.Adhesive")
		(11 "B.Adhes" user "B.Adhesive")
		(13 "F.Paste" user "Package Geometry/Pastemask Top")
		(15 "B.Paste" user "Package Geometry/Pastemask Bottom")
		(5 "F.SilkS" user "Ref Des/Silkscreen Top")
		(7 "B.SilkS" user "Ref Des/Silkscreen Bottom")
		(1 "F.Mask" user "Board Geometry/Soldermask Top")
		(3 "B.Mask" user "Board Geometry/Soldermask Bottom")
		(17 "Dwgs.User" user "User.Drawings")
		(19 "Cmts.User" user "User.Comments")
		(21 "Eco1.User" user "User.Eco1")
		(23 "Eco2.User" user "User.Eco2")
		(25 "Edge.Cuts" user "Board Geometry/Outline")
		(27 "Margin" user)
		(31 "F.CrtYd" user "Package Geometry/Place Bound Top")
		(29 "B.CrtYd" user "Package Geometry/Place Bound Bottom")
		(35 "F.Fab" user "Ref Des/Assembly Top")
		(33 "B.Fab" user "Ref Des/Assembly Bottom")
	)
	(footprint ""
		(layer "B.Cu")
		(at 251.918216 -227.084382 90)
		(property "Reference" "U67"
			(at -1.990598 3.22961 270)
			(unlocked yes)
			(layer "B.SilkS")
			(effects
				(font
					(size 0.7874 0.5842)
					(thickness 0.1524)
				)
				(justify mirror)
			)
		)
		(property "Value" ""
			(at 0 0 90)
			(layer "B.Fab")
			(effects
				(font
					(size 1.27 1.27)
				)
				(justify mirror)
			)
		)
		(duplicate_pad_numbers_are_jumpers no)
		(fp_line
			(start 1.8288 -2.4892)
			(end 0.5588 -2.4892)
			(stroke
				(width 0.1524)
				(type default)
			)
			(layer "B.SilkS")
		)
		(fp_line
			(start 0.5588 -2.4892)
			(end 0 -1.9304)
			(stroke
				(width 0.1524)
				(type default)
			)
			(layer "B.SilkS")
		)
		(fp_line
			(start -0.5588 -2.4892)
			(end -1.8288 -2.4892)
			(stroke
				(width 0.1524)
				(type default)
			)
			(layer "B.SilkS")
		)
		(fp_line
			(start -1.8288 -2.4892)
			(end -1.8161 2.4892)
			(stroke
				(width 0.1524)
				(type default)
			)
			(layer "B.SilkS")
		)
		(fp_line
			(start 0 -1.9304)
			(end -0.5588 -2.4892)
			(stroke
				(width 0.1524)
				(type default)
			)
			(layer "B.SilkS")
		)
		(fp_line
			(start 1.8288 2.4892)
			(end 1.8288 -2.4892)
			(stroke
				(width 0.1524)
				(type default)
			)
			(layer "B.SilkS")
		)
		(fp_line
			(start -1.8161 2.4892)
			(end 1.8288 2.4892)
			(stroke
				(width 0.1524)
				(type default)
			)
			(layer "B.SilkS")
		)
		(fp_poly
			(pts
				(xy 4.23672 -1.989328) (xy 4.23672 -2.614168) (xy 3.683 -2.286)
			)
			(stroke
				(width 0)
				(type default)
			)
			(fill yes)
			(layer "B.SilkS")
		)
		(fp_line
			(start 1.9939 -2.4892)
			(end -1.9939 -2.4892)
			(stroke
				(width 0.1)
				(type default)
			)
			(layer "B.Fab")
		)
		(fp_line
			(start -1.9939 -2.4892)
			(end -1.9939 -2.3876)
			(stroke
				(width 0.1)
				(type default)
			)
			(layer "B.Fab")
		)
		(fp_line
			(start 3.0988 -2.3876)
			(end 1.9939 -2.3876)
			(stroke
				(width 0.1)
				(type default)
			)
			(layer "B.Fab")
		)
		(fp_line
			(start 1.9939 -2.3876)
			(end 1.9939 -2.4892)
			(stroke
				(width 0.1)
				(type default)
			)
			(layer "B.Fab")
		)
		(fp_line
			(start 1.9939 -2.3876)
			(end 1.9812 -2.3876)
			(stroke
				(width 0.1)
				(type default)
			)
			(layer "B.Fab")
		)
		(fp_line
			(start -1.9939 -2.3876)
			(end -3.0988 -2.3876)
			(stroke
				(width 0.1)
				(type default)
			)
			(layer "B.Fab")
		)
		(fp_line
			(start -1.9939 -2.3876)
			(end -1.9939 2.3876)
			(stroke
				(width 0.1)
				(type default)
			)
			(layer "B.Fab")
		)
		(fp_line
			(start -3.0988 -2.3876)
			(end -3.0988 2.3876)
			(stroke
				(width 0.1)
				(type default)
			)
			(layer "B.Fab")
		)
		(fp_line
			(start -3.0988 -2.3876)
			(end -3.0988 2.3876)
			(stroke
				(width 0.1)
				(type default)
			)
			(layer "B.Fab")
		)
		(fp_line
			(start 3.0988 2.3876)
			(end 3.0988 -2.3876)
			(stroke
				(width 0.1)
				(type default)
			)
			(layer "B.Fab")
		)
		(fp_line
			(start 3.0988 2.3876)
			(end 3.0988 -2.3876)
			(stroke
				(width 0.1)
				(type default)
			)
			(layer "B.Fab")
		)
		(fp_line
			(start 1.9939 2.3876)
			(end 1.9939 -2.3876)
			(stroke
				(width 0.1)
				(type default)
			)
			(layer "B.Fab")
		)
		(fp_line
			(start 1.9939 2.3876)
			(end 3.0988 2.3876)
			(stroke
				(width 0.1)
				(type default)
			)
			(layer "B.Fab")
		)
		(fp_line
			(start -1.9939 2.3876)
			(end -1.9939 2.4892)
			(stroke
				(width 0.1)
				(type default)
			)
			(layer "B.Fab")
		)
		(fp_line
			(start -3.0988 2.3876)
			(end -1.9939 2.3876)
			(stroke
				(width 0.1)
				(type default)
			)
			(layer "B.Fab")
		)
		(fp_line
			(start 1.9939 2.4892)
			(end 1.9939 2.3876)
			(stroke
				(width 0.1)
				(type default)
			)
			(layer "B.Fab")
		)
		(fp_line
			(start -1.9939 2.4892)
			(end 1.9939 2.4892)
			(stroke
				(width 0.1)
				(type default)
			)
			(layer "B.Fab")
		)
		(fp_line
			(start -1.9939 2.4892)
			(end -2.0066 2.4892)
			(stroke
				(width 0.1)
				(type default)
			)
			(layer "B.Fab")
		)
		(fp_line
			(start -1.9939 2.5019)
			(end -1.9939 2.4892)
			(stroke
				(width 0.1)
				(type default)
			)
			(layer "B.Fab")
		)
		(fp_poly
			(pts
				(xy 4.23672 -1.989328) (xy 4.23672 -2.614168) (xy 3.683 -2.286)
			)
			(stroke
				(width 0)
				(type default)
			)
			(fill yes)
			(layer "B.Fab")
		)
		(pad "1" smd rect
			(at 2.7432 -2.2225)
			(size 0.3556 1.5494)
			(layers "B.Cu" "B.Mask" "B.Paste")
			(net "SEL_FLASH_PEX2_BUF_R")
		)
		(pad "2" smd rect
			(at 2.7432 -1.5875)
			(size 0.3556 1.5494)
			(layers "B.Cu" "B.Mask" "B.Paste")
			(net "SPI_PEX2_CS_R_N")
		)
		(pad "3" smd rect
			(at 2.7432 -0.9525)
			(size 0.3556 1.5494)
			(layers "B.Cu" "B.Mask" "B.Paste")
			(net "SPI_BIC1_CS0_LS23_R1_N")
		)
		(pad "4" smd rect
			(at 2.7432 -0.3175)
			(size 0.3556 1.5494)
			(layers "B.Cu" "B.Mask" "B.Paste")
			(net "SPI_PEX2_CS_MUX_N")
		)
		(pad "5" smd rect
			(at 2.7432 0.3175)
			(size 0.3556 1.5494)
			(layers "B.Cu" "B.Mask" "B.Paste")
			(net "SPI_PEX2_CLK_R")
		)
		(pad "6" smd rect
			(at 2.7432 0.9525)
			(size 0.3556 1.5494)
			(layers "B.Cu" "B.Mask" "B.Paste")
			(net "SPI_BIC1_CLK_LS23_R1")
		)
		(pad "7" smd rect
			(at 2.7432 1.5875)
			(size 0.3556 1.5494)
			(layers "B.Cu" "B.Mask" "B.Paste")
			(net "SPI_PEX2_CLK_MUX")
		)
		(pad "8" smd rect
			(at 2.7432 2.2225)
			(size 0.3556 1.5494)
			(layers "B.Cu" "B.Mask" "B.Paste")
			(net "GND")
		)
		(pad "9" smd rect
			(at -2.7432 2.2225)
			(size 0.3556 1.5494)
			(layers "B.Cu" "B.Mask" "B.Paste")
			(net "SPI_PEX2_SDIO0_MUX")
		)
		(pad "10" smd rect
			(at -2.7432 1.5875)
			(size 0.3556 1.5494)
			(layers "B.Cu" "B.Mask" "B.Paste")
			(net "SPI_BIC1_MOSI_LS23_R1")
		)
		(pad "11" smd rect
			(at -2.7432 0.9525)
			(size 0.3556 1.5494)
			(layers "B.Cu" "B.Mask" "B.Paste")
			(net "SPI_PEX2_SDIO0_R")
		)
		(pad "12" smd rect
			(at -2.7432 0.3175)
			(size 0.3556 1.5494)
			(layers "B.Cu" "B.Mask" "B.Paste")
			(net "SPI_PEX2_SDIO1_MUX")
		)
		(pad "13" smd rect
			(at -2.7432 -0.3175)
			(size 0.3556 1.5494)
			(layers "B.Cu" "B.Mask" "B.Paste")
			(net "SPI_BIC1_MISO_LS23_R1")
		)
		(pad "14" smd rect
			(at -2.7432 -0.9525)
			(size 0.3556 1.5494)
			(layers "B.Cu" "B.Mask" "B.Paste")
			(net "SPI_PEX2_SDIO1_R")
		)
		(pad "15" smd rect
			(at -2.7432 -1.5875)
			(size 0.3556 1.5494)
			(layers "B.Cu" "B.Mask" "B.Paste")
			(net "SPI_MUX_PEX2_EN_N")
		)
		(pad "16" smd rect
			(at -2.7432 -2.2225)
			(size 0.3556 1.5494)
			(layers "B.Cu" "B.Mask" "B.Paste")
			(net "P3V3_AUX")
		)
	)
	(footprint ""
		(layer "B.Cu")
		(at 112.033812 -321.36334 -90)
		(property "Reference" "R6451"
			(at 0 0 90)
			(layer "B.SilkS")
			(hide yes)
			(effects
				(font
					(size 1.27 1.27)
				)
				(justify mirror)
			)
		)
		(property "Value" ""
			(at 0 0 90)
			(layer "B.Fab")
			(effects
				(font
					(size 1.27 1.27)
				)
				(justify mirror)
			)
		)
		(duplicate_pad_numbers_are_jumpers no)
		(fp_line
			(start -0.7874 0.4064)
			(end 0.7874 0.4064)
			(stroke
				(width 0.1524)
				(type default)
			)
			(layer "B.SilkS")
		)
		(fp_line
			(start 0.7874 0.4064)
			(end 0.7874 -0.4064)
			(stroke
				(width 0.1524)
				(type default)
			)
			(layer "B.SilkS")
		)
		(fp_line
			(start -0.7874 -0.4064)
			(end -0.7874 0.4064)
			(stroke
				(width 0.1524)
				(type default)
			)
			(layer "B.SilkS")
		)
		(fp_line
			(start 0.7874 -0.4064)
			(end -0.7874 -0.4064)
			(stroke
				(width 0.1524)
				(type default)
			)
			(layer "B.SilkS")
		)
		(fp_line
			(start -0.67945 0.3048)
			(end -0.120396 0.3048)
			(stroke
				(width 0.1)
				(type default)
			)
			(layer "B.Fab")
		)
		(fp_line
			(start -0.120396 0.3048)
			(end -0.120396 0.2794)
			(stroke
				(width 0.1)
				(type default)
			)
			(layer "B.Fab")
		)
		(fp_line
			(start 0.12065 0.3048)
			(end 0.67945 0.3048)
			(stroke
				(width 0.1)
				(type default)
			)
			(layer "B.Fab")
		)
		(fp_line
			(start 0.67945 0.3048)
			(end 0.67945 -0.305054)
			(stroke
				(width 0.1)
				(type default)
			)
			(layer "B.Fab")
		)
		(fp_line
			(start -0.120396 0.2794)
			(end 0.12065 0.2794)
			(stroke
				(width 0.1)
				(type default)
			)
			(layer "B.Fab")
		)
		(fp_line
			(start 0.12065 0.2794)
			(end 0.12065 0.3048)
			(stroke
				(width 0.1)
				(type default)
			)
			(layer "B.Fab")
		)
		(fp_line
			(start -0.12065 -0.2794)
			(end -0.12065 -0.3048)
			(stroke
				(width 0.1)
				(type default)
			)
			(layer "B.Fab")
		)
		(fp_line
			(start 0.12065 -0.2794)
			(end -0.12065 -0.2794)
			(stroke
				(width 0.1)
				(type default)
			)
			(layer "B.Fab")
		)
		(fp_line
			(start -0.67945 -0.3048)
			(end -0.67945 0.3048)
			(stroke
				(width 0.1)
				(type default)
			)
			(layer "B.Fab")
		)
		(fp_line
			(start -0.12065 -0.3048)
			(end -0.67945 -0.3048)
			(stroke
				(width 0.1)
				(type default)
			)
			(layer "B.Fab")
		)
		(fp_line
			(start 0.12065 -0.305054)
			(end 0.12065 -0.2794)
			(stroke
				(width 0.1)
				(type default)
			)
			(layer "B.Fab")
		)
		(fp_line
			(start 0.67945 -0.305054)
			(end 0.12065 -0.305054)
			(stroke
				(width 0.1)
				(type default)
			)
			(layer "B.Fab")
		)
		(pad "1" smd circle
			(at 0.40005 0 90)
			(size 0 0)
			(layers "B.Cu" "B.Mask" "B.Paste")
			(net "P0V8_SERDES_VDDA_PEX0")
		)
		(pad "2" smd circle
			(at -0.40005 0 90)
			(size 0 0)
			(layers "B.Cu" "B.Mask" "B.Paste")
			(net "P0V8_SERDES_VDDA_PEX0_C2")
		)
	)
	(footprint ""
		(layer "B.Cu")
		(at 51.574954 -286.399732 90)
		(property "Reference" "C2985"
			(at 0 0 90)
			(layer "B.SilkS")
			(hide yes)
			(effects
				(font
					(size 1.27 1.27)
				)
				(justify mirror)
			)
		)
		(property "Value" ""
			(at 0 0 90)
			(layer "B.Fab")
			(effects
				(font
					(size 1.27 1.27)
				)
				(justify mirror)
			)
		)
		(duplicate_pad_numbers_are_jumpers no)
		(fp_line
			(start 0.299974 -0.150114)
			(end -0.299974 -0.150114)
			(stroke
				(width 0.1)
				(type default)
			)
			(layer "B.Fab")
		)
		(fp_line
			(start -0.299974 -0.150114)
			(end -0.299974 0.150114)
			(stroke
				(width 0.1)
				(type default)
			)
			(layer "B.Fab")
		)
		(fp_line
			(start 0.299974 0.150114)
			(end 0.299974 -0.150114)
			(stroke
				(width 0.1)
				(type default)
			)
			(layer "B.Fab")
		)
		(fp_line
			(start -0.299974 0.150114)
			(end 0.299974 0.150114)
			(stroke
				(width 0.1)
				(type default)
			)
			(layer "B.Fab")
		)
		(pad "1" smd rect
			(at 0.2667 0 270)
			(size 0.3048 0.381)
			(layers "B.Cu" "B.Mask" "B.Paste")
			(net "P1V25_SERDES_VDDPLL_PEX0")
		)
		(pad "2" smd rect
			(at -0.2667 0 270)
			(size 0.3048 0.381)
			(layers "B.Cu" "B.Mask" "B.Paste")
			(net "GND")
		)
	)
	(footprint ""
		(layer "B.Cu")
		(at 236.234732 -292.533832)
		(property "Reference" "PC996"
			(at 0 0 0)
			(layer "B.SilkS")
			(hide yes)
			(effects
				(font
					(size 1.27 1.27)
				)
				(justify mirror)
			)
		)
		(property "Value" ""
			(at 0 0 0)
			(layer "B.Fab")
			(effects
				(font
					(size 1.27 1.27)
				)
				(justify mirror)
			)
		)
		(duplicate_pad_numbers_are_jumpers no)
		(fp_line
			(start -1.524 -0.762)
			(end -1.524 0.762)
			(stroke
				(width 0.1524)
				(type default)
			)
			(layer "B.SilkS")
		)
		(fp_line
			(start -1.524 0.762)
			(end 1.524 0.762)
			(stroke
				(width 0.1524)
				(type default)
			)
			(layer "B.SilkS")
		)
		(fp_line
			(start 1.524 -0.762)
			(end -1.524 -0.762)
			(stroke
				(width 0.1524)
				(type default)
			)
			(layer "B.SilkS")
		)
		(fp_line
			(start 1.524 0.762)
			(end 1.524 -0.762)
			(stroke
				(width 0.1524)
				(type default)
			)
			(layer "B.SilkS")
		)
		(fp_line
			(start -1.1049 -0.724916)
			(end 1.1049 -0.724916)
			(stroke
				(width 0.1)
				(type default)
			)
			(layer "B.Fab")
		)
		(fp_line
			(start -1.1049 0.724916)
			(end -1.1049 -0.724916)
			(stroke
				(width 0.1)
				(type default)
			)
			(layer "B.Fab")
		)
		(fp_line
			(start 1.1049 -0.724916)
			(end 1.1049 0.724916)
			(stroke
				(width 0.1)
				(type default)
			)
			(layer "B.Fab")
		)
		(fp_line
			(start 1.1049 0.724916)
			(end -1.1049 0.724916)
			(stroke
				(width 0.1)
				(type default)
			)
			(layer "B.Fab")
		)
		(pad "1" smd rect
			(at 0.889 0)
			(size 1.016 1.27)
			(layers "B.Cu" "B.Mask" "B.Paste")
			(net "P1V25_PEX2_R")
		)
		(pad "2" smd rect
			(at -0.889 0)
			(size 1.016 1.27)
			(layers "B.Cu" "B.Mask" "B.Paste")
			(net "GND")
		)
	)
	(footprint ""
		(layer "B.Cu")
		(at 16.19123 -223.937068 90)
		(property "Reference" "R3442"
			(at 0 0 90)
			(layer "B.SilkS")
			(hide yes)
			(effects
				(font
					(size 1.27 1.27)
				)
				(justify mirror)
			)
		)
		(property "Value" ""
			(at 0 0 90)
			(layer "B.Fab")
			(effects
				(font
					(size 1.27 1.27)
				)
				(justify mirror)
			)
		)
		(duplicate_pad_numbers_are_jumpers no)
		(fp_line
			(start 0.7874 -0.4064)
			(end -0.7874 -0.4064)
			(stroke
				(width 0.1524)
				(type default)
			)
			(layer "B.SilkS")
		)
		(fp_line
			(start -0.7874 -0.4064)
			(end -0.7874 0.4064)
			(stroke
				(width 0.1524)
				(type default)
			)
			(layer "B.SilkS")
		)
		(fp_line
			(start 0.7874 0.4064)
			(end 0.7874 -0.4064)
			(stroke
				(width 0.1524)
				(type default)
			)
			(layer "B.SilkS")
		)
		(fp_line
			(start -0.7874 0.4064)
			(end 0.7874 0.4064)
			(stroke
				(width 0.1524)
				(type default)
			)
			(layer "B.SilkS")
		)
		(fp_line
			(start 0.67945 -0.305054)
			(end 0.12065 -0.305054)
			(stroke
				(width 0.1)
				(type default)
			)
			(layer "B.Fab")
		)
		(fp_line
			(start 0.12065 -0.305054)
			(end 0.12065 -0.2794)
			(stroke
				(width 0.1)
				(type default)
			)
			(layer "B.Fab")
		)
		(fp_line
			(start -0.12065 -0.3048)
			(end -0.67945 -0.3048)
			(stroke
				(width 0.1)
				(type default)
			)
			(layer "B.Fab")
		)
		(fp_line
			(start -0.67945 -0.3048)
			(end -0.67945 0.3048)
			(stroke
				(width 0.1)
				(type default)
			)
			(layer "B.Fab")
		)
		(fp_line
			(start 0.12065 -0.2794)
			(end -0.12065 -0.2794)
			(stroke
				(width 0.1)
				(type default)
			)
			(layer "B.Fab")
		)
		(fp_line
			(start -0.12065 -0.2794)
			(end -0.12065 -0.3048)
			(stroke
				(width 0.1)
				(type default)
			)
			(layer "B.Fab")
		)
		(fp_line
			(start 0.12065 0.2794)
			(end 0.12065 0.3048)
			(stroke
				(width 0.1)
				(type default)
			)
			(layer "B.Fab")
		)
		(fp_line
			(start -0.120396 0.2794)
			(end 0.12065 0.2794)
			(stroke
				(width 0.1)
				(type default)
			)
			(layer "B.Fab")
		)
		(fp_line
			(start 0.67945 0.3048)
			(end 0.67945 -0.305054)
			(stroke
				(width 0.1)
				(type default)
			)
			(layer "B.Fab")
		)
		(fp_line
			(start 0.12065 0.3048)
			(end 0.67945 0.3048)
			(stroke
				(width 0.1)
				(type default)
			)
			(layer "B.Fab")
		)
		(fp_line
			(start -0.120396 0.3048)
			(end -0.120396 0.2794)
			(stroke
				(width 0.1)
				(type default)
			)
			(layer "B.Fab")
		)
		(fp_line
			(start -0.67945 0.3048)
			(end -0.120396 0.3048)
			(stroke
				(width 0.1)
				(type default)
			)
			(layer "B.Fab")
		)
		(pad "1" smd circle
			(at 0.40005 0 270)
			(size 0 0)
			(layers "B.Cu" "B.Mask" "B.Paste")
			(net "SPI_MUX_PEX0_EN_N")
		)
		(pad "2" smd circle
			(at -0.40005 0 270)
			(size 0 0)
			(layers "B.Cu" "B.Mask" "B.Paste")
			(net "GND")
		)
	)
	(footprint ""
		(layer "B.Cu")
		(at 104.38257 -81.78419 90)
		(property "Reference" "C2662"
			(at 0 0 90)
			(layer "B.SilkS")
			(hide yes)
			(effects
				(font
					(size 1.27 1.27)
				)
				(justify mirror)
			)
		)
		(property "Value" ""
			(at 0 0 90)
			(layer "B.Fab")
			(effects
				(font
					(size 1.27 1.27)
				)
				(justify mirror)
			)
		)
		(duplicate_pad_numbers_are_jumpers no)
		(fp_line
			(start 1.524 -0.762)
			(end -1.524 -0.762)
			(stroke
				(width 0.1524)
				(type default)
			)
			(layer "B.SilkS")
		)
		(fp_line
			(start -1.524 -0.762)
			(end -1.524 0.762)
			(stroke
				(width 0.1524)
				(type default)
			)
			(layer "B.SilkS")
		)
		(fp_line
			(start 1.524 0.762)
			(end 1.524 -0.762)
			(stroke
				(width 0.1524)
				(type default)
			)
			(layer "B.SilkS")
		)
		(fp_line
			(start -1.524 0.762)
			(end 1.524 0.762)
			(stroke
				(width 0.1524)
				(type default)
			)
			(layer "B.SilkS")
		)
		(fp_line
			(start 1.1049 -0.724916)
			(end 1.1049 0.724916)
			(stroke
				(width 0.1)
				(type default)
			)
			(layer "B.Fab")
		)
		(fp_line
			(start -1.1049 -0.724916)
			(end 1.1049 -0.724916)
			(stroke
				(width 0.1)
				(type default)
			)
			(layer "B.Fab")
		)
		(fp_line
			(start 1.1049 0.724916)
			(end -1.1049 0.724916)
			(stroke
				(width 0.1)
				(type default)
			)
			(layer "B.Fab")
		)
		(fp_line
			(start -1.1049 0.724916)
			(end -1.1049 -0.724916)
			(stroke
				(width 0.1)
				(type default)
			)
			(layer "B.Fab")
		)
		(pad "1" smd rect
			(at 0.889 0 90)
			(size 1.016 1.27)
			(layers "B.Cu" "B.Mask" "B.Paste")
			(net "P3V3_VDD_9ZXL0851_0_7")
		)
		(pad "2" smd rect
			(at -0.889 0 90)
			(size 1.016 1.27)
			(layers "B.Cu" "B.Mask" "B.Paste")
			(net "GND")
		)
	)
)
